# T6G (Grand Teton) — schematic netlist excerpt (pin names and nets, part order shuffled) for the footprints in the layout excerpt that follows; sources: Cadence DE-HDL packaged netlist, KiCad conversion of 04192023_DAF0TMB3IC0_F0TG_MB_C_brd_V02_OCP.brd

PC581  Q_CAP  4.7UF 16V 10% X6S  pkg C0603  page 190 : A = P3V3_AUX_VDRV ; B = GND
PC6518  Q_CAP  0.1UF 25V 10% X7R  pkg 0402  page 360 : A = P1V8_RETIMER_CPU0_REF ; B = GND

(kicad_pcb
	(version 20260206)
	(generator "pcbnew")
	(generator_version "10.0")
	(general
		(thickness 1.6)
		(legacy_teardrops no)
	)
	(paper "A4")
	(title_block
		(title "04192023_DAF0TMB3IC0_F0TG_MB_C_brd_V02_OCP.brd")
		(comment 1 "Grand Teton / footprints 4687-4688 of 8354")
	)
	(layers
		(0 "F.Cu" signal "TOP")
		(4 "In1.Cu" signal "GND")
		(6 "In2.Cu" signal "IN1")
		(8 "In3.Cu" signal "GND1")
		(10 "In4.Cu" signal "IN2")
		(12 "In5.Cu" signal "GND2")
		(14 "In6.Cu" signal "IN3")
		(16 "In7.Cu" signal "GND3")
		(18 "In8.Cu" signal "VCC")
		(20 "In9.Cu" signal "VCC1")
		(22 "In10.Cu" signal "GND4")
		(24 "In11.Cu" signal "IN4")
		(26 "In12.Cu" signal "GND5")
		(28 "In13.Cu" signal "IN5")
		(30 "In14.Cu" signal "GND6")
		(32 "In15.Cu" signal "IN6")
		(34 "In16.Cu" signal "GND7")
		(2 "B.Cu" signal "BOTTOM")
		(9 "F.Adhes" user "F.Adhesive")
		(11 "B.Adhes" user "B.Adhesive")
		(13 "F.Paste" user "Package Geometry/Pastemask Top")
		(15 "B.Paste" user "Package Geometry/Pastemask Bottom")
		(5 "F.SilkS" user "Ref Des/Silkscreen Top")
		(7 "B.SilkS" user "Ref Des/Silkscreen Bottom")
		(1 "F.Mask" user "Board Geometry/Soldermask Top")
		(3 "B.Mask" user "Board Geometry/Soldermask Bottom")
		(17 "Dwgs.User" user "User.Drawings")
		(19 "Cmts.User" user "User.Comments")
		(21 "Eco1.User" user "User.Eco1")
		(23 "Eco2.User" user "User.Eco2")
		(25 "Edge.Cuts" user "Board Geometry/Outline")
		(27 "Margin" user)
		(31 "F.CrtYd" user "Package Geometry/Place Bound Top")
		(29 "B.CrtYd" user "Package Geometry/Place Bound Bottom")
		(35 "F.Fab" user "Ref Des/Assembly Top")
		(33 "B.Fab" user "Ref Des/Assembly Bottom")
	)
	(footprint ""
		(layer "F.Cu")
		(at 239.53597 -291.863526 180)
		(property "Reference" "PC6518"
			(at 0 0 180)
			(layer "F.SilkS")
			(hide yes)
			(effects
				(font
					(size 1.27 1.27)
				)
			)
		)
		(property "Value" ""
			(at 0 0 180)
			(layer "F.Fab")
			(effects
				(font
					(size 1.27 1.27)
				)
			)
		)
		(duplicate_pad_numbers_are_jumpers no)
		(fp_line
			(start 0.7874 0.4064)
			(end -0.7874 0.4064)
			(stroke
				(width 0.1524)
				(type default)
			)
			(layer "F.SilkS")
		)
		(fp_line
			(start 0.7874 -0.4064)
			(end 0.7874 0.4064)
			(stroke
				(width 0.1524)
				(type default)
			)
			(layer "F.SilkS")
		)
		(fp_line
			(start -0.7874 0.4064)
			(end -0.7874 -0.4064)
			(stroke
				(width 0.1524)
				(type default)
			)
			(layer "F.SilkS")
		)
		(fp_line
			(start -0.7874 -0.4064)
			(end 0.7874 -0.4064)
			(stroke
				(width 0.1524)
				(type default)
			)
			(layer "F.SilkS")
		)
		(fp_line
			(start 0.67945 0.3048)
			(end 0.120396 0.3048)
			(stroke
				(width 0.1)
				(type default)
			)
			(layer "F.Fab")
		)
		(fp_line
			(start 0.67945 -0.3048)
			(end 0.67945 0.3048)
			(stroke
				(width 0.1)
				(type default)
			)
			(layer "F.Fab")
		)
		(fp_line
			(start 0.12065 -0.2794)
			(end 0.12065 -0.3048)
			(stroke
				(width 0.1)
				(type default)
			)
			(layer "F.Fab")
		)
		(fp_line
			(start 0.12065 -0.3048)
			(end 0.67945 -0.3048)
			(stroke
				(width 0.1)
				(type default)
			)
			(layer "F.Fab")
		)
		(fp_line
			(start 0.120396 0.3048)
			(end 0.120396 0.2794)
			(stroke
				(width 0.1)
				(type default)
			)
			(layer "F.Fab")
		)
		(fp_line
			(start 0.120396 0.2794)
			(end -0.12065 0.2794)
			(stroke
				(width 0.1)
				(type default)
			)
			(layer "F.Fab")
		)
		(fp_line
			(start -0.12065 0.3048)
			(end -0.67945 0.3048)
			(stroke
				(width 0.1)
				(type default)
			)
			(layer "F.Fab")
		)
		(fp_line
			(start -0.12065 0.2794)
			(end -0.12065 0.3048)
			(stroke
				(width 0.1)
				(type default)
			)
			(layer "F.Fab")
		)
		(fp_line
			(start -0.12065 -0.2794)
			(end 0.12065 -0.2794)
			(stroke
				(width 0.1)
				(type default)
			)
			(layer "F.Fab")
		)
		(fp_line
			(start -0.12065 -0.305054)
			(end -0.12065 -0.2794)
			(stroke
				(width 0.1)
				(type default)
			)
			(layer "F.Fab")
		)
		(fp_line
			(start -0.67945 0.3048)
			(end -0.67945 -0.305054)
			(stroke
				(width 0.1)
				(type default)
			)
			(layer "F.Fab")
		)
		(fp_line
			(start -0.67945 -0.305054)
			(end -0.12065 -0.305054)
			(stroke
				(width 0.1)
				(type default)
			)
			(layer "F.Fab")
		)
		(pad "1" smd circle
			(at -0.40005 0 180)
			(size 0 0)
			(layers "F.Cu" "F.Mask" "F.Paste")
			(net "P1V8_RETIMER_CPU0_REF")
		)
		(pad "2" smd circle
			(at 0.40005 0 180)
			(size 0 0)
			(layers "F.Cu" "F.Mask" "F.Paste")
			(net "GND")
		)
	)
	(footprint ""
		(layer "F.Cu")
		(at 460.204058 -52.196492 90)
		(property "Reference" "PC581"
			(at 0 0 90)
			(layer "F.SilkS")
			(hide yes)
			(effects
				(font
					(size 1.27 1.27)
				)
			)
		)
		(property "Value" ""
			(at 0 0 90)
			(layer "F.Fab")
			(effects
				(font
					(size 1.27 1.27)
				)
			)
		)
		(duplicate_pad_numbers_are_jumpers no)
		(fp_line
			(start 1.2954 -0.5842)
			(end 1.2954 0.5842)
			(stroke
				(width 0.1524)
				(type default)
			)
			(layer "F.SilkS")
		)
		(fp_line
			(start -1.2954 -0.5842)
			(end 1.2954 -0.5842)
			(stroke
				(width 0.1524)
				(type default)
			)
			(layer "F.SilkS")
		)
		(fp_line
			(start 1.2954 0.5842)
			(end -1.2954 0.5842)
			(stroke
				(width 0.1524)
				(type default)
			)
			(layer "F.SilkS")
		)
		(fp_line
			(start -1.2954 0.5842)
			(end -1.2954 -0.5842)
			(stroke
				(width 0.1524)
				(type default)
			)
			(layer "F.SilkS")
		)
		(fp_line
			(start 0.8636 -0.4572)
			(end 0.8636 -0.4064)
			(stroke
				(width 0.1)
				(type default)
			)
			(layer "F.Fab")
		)
		(fp_line
			(start -0.8636 -0.4572)
			(end 0.8636 -0.4572)
			(stroke
				(width 0.1)
				(type default)
			)
			(layer "F.Fab")
		)
		(fp_line
			(start 1.1938 -0.4064)
			(end 1.1938 0.4064)
			(stroke
				(width 0.1)
				(type default)
			)
			(layer "F.Fab")
		)
		(fp_line
			(start 0.8636 -0.4064)
			(end 1.1938 -0.4064)
			(stroke
				(width 0.1)
				(type default)
			)
			(layer "F.Fab")
		)
		(fp_line
			(start -0.8636 -0.4064)
			(end -0.8636 -0.4572)
			(stroke
				(width 0.1)
				(type default)
			)
			(layer "F.Fab")
		)
		(fp_line
			(start -1.1938 -0.4064)
			(end -0.8636 -0.4064)
			(stroke
				(width 0.1)
				(type default)
			)
			(layer "F.Fab")
		)
		(fp_line
			(start 1.1938 0.4064)
			(end 0.8636 0.4064)
			(stroke
				(width 0.1)
				(type default)
			)
			(layer "F.Fab")
		)
		(fp_line
			(start 0.8636 0.4064)
			(end 0.8636 0.4572)
			(stroke
				(width 0.1)
				(type default)
			)
			(layer "F.Fab")
		)
		(fp_line
			(start -0.8636 0.4064)
			(end -1.1938 0.4064)
			(stroke
				(width 0.1)
				(type default)
			)
			(layer "F.Fab")
		)
		(fp_line
			(start -1.1938 0.4064)
			(end -1.1938 -0.4064)
			(stroke
				(width 0.1)
				(type default)
			)
			(layer "F.Fab")
		)
		(fp_line
			(start 0.8636 0.4572)
			(end -0.8636 0.4572)
			(stroke
				(width 0.1)
				(type default)
			)
			(layer "F.Fab")
		)
		(fp_line
			(start -0.8636 0.4572)
			(end -0.8636 0.4064)
			(stroke
				(width 0.1)
				(type default)
			)
			(layer "F.Fab")
		)
		(pad "1" smd rect
			(at -0.7366 0)
			(size 0.7112 0.8128)
			(layers "F.Cu" "F.Mask" "F.Paste")
			(net "P3V3_AUX_VDRV")
		)
		(pad "2" smd rect
			(at 0.7366 0)
			(size 0.7112 0.8128)
			(layers "F.Cu" "F.Mask" "F.Paste")
			(net "GND")
		)
	)
)
